(kicad_pcb
	(version 20241229)
	(generator "pcbnew")
	(generator_version "9.0")
	(general
		(thickness 1.599998)
		(legacy_teardrops no)
	)
	(paper "A4")
	(title_block
		(date "2023-02-12")
		(rev "1.1.5")
		(comment 9 "footprints 95-100 of 473")
	)
	(layers
		(0 "F.Cu" signal)
		(4 "In1.Cu" power "In1.GND")
		(6 "In2.Cu" signal)
		(8 "In3.Cu" power "In3.GND")
		(10 "In4.Cu" power "In4.VCC")
		(12 "In5.Cu" signal)
		(14 "In6.Cu" power "In6.VCC")
		(2 "B.Cu" signal)
		(9 "F.Adhes" user "F.Adhesive")
		(11 "B.Adhes" user "B.Adhesive")
		(13 "F.Paste" user)
		(15 "B.Paste" user)
		(5 "F.SilkS" user "F.Silkscreen")
		(7 "B.SilkS" user "B.Silkscreen")
		(1 "F.Mask" user)
		(3 "B.Mask" user)
		(17 "Dwgs.User" user "User.Drawings")
		(19 "Cmts.User" user "User.Comments")
		(21 "Eco1.User" user "User.Eco1")
		(23 "Eco2.User" user "User.Eco2")
		(25 "Edge.Cuts" user)
		(27 "Margin" user)
		(31 "F.CrtYd" user "F.Courtyard")
		(29 "B.CrtYd" user "B.Courtyard")
		(35 "F.Fab" user)
		(33 "B.Fab" user)
	)
	(footprint "antmicro-footprints:R_0402_1005Metric"
		(layer "F.Cu")
		(at 154.059 113.135 -90)
		(descr "Resistor SMD 0402")
		(tags "resistor SMD 0402")
		(property "Reference" "R39"
			(at -0.835 -0.416 270)
			(layer "F.SilkS")
			(effects
				(font
					(size 0.7 0.7)
					(thickness 0.15)
				)
				(justify left bottom)
			)
		)
		(property "Value" "R_0R_0402"
			(at 0 1.4 270)
			(layer "F.Fab")
			(effects
				(font
					(size 0.7 0.7)
					(thickness 0.15)
				)
				(justify left bottom)
			)
		)
		(property "Description" "0R resistor in 0402 package with unspecified tolerance"
			(at 0 0 270)
			(layer "F.Fab")
			(hide yes)
			(effects
				(font
					(size 1.27 1.27)
					(thickness 0.15)
				)
			)
		)
		(property "Author" "Antmicro"
			(at 40.924 267.194 0)
			(layer "F.Fab")
			(hide yes)
			(effects
				(font
					(size 1 1)
					(thickness 0.15)
				)
			)
		)
		(property "Current" "1A"
			(at 40.924 267.194 0)
			(layer "F.Fab")
			(hide yes)
			(effects
				(font
					(size 1 1)
					(thickness 0.15)
				)
			)
		)
		(property "License" "Apache-2.0"
			(at 40.924 267.194 0)
			(layer "F.Fab")
			(hide yes)
			(effects
				(font
					(size 1 1)
					(thickness 0.15)
				)
			)
		)
		(property "MPN" "ERJ2GE0R00X"
			(at 40.924 267.194 0)
			(layer "F.Fab")
			(hide yes)
			(effects
				(font
					(size 1 1)
					(thickness 0.15)
				)
			)
		)
		(property "Manufacturer" "Panasonic"
			(at 40.924 267.194 0)
			(layer "F.Fab")
			(hide yes)
			(effects
				(font
					(size 1 1)
					(thickness 0.15)
				)
			)
		)
		(property "Tolerance" ""
			(at 40.924 267.194 0)
			(layer "F.Fab")
			(hide yes)
			(effects
				(font
					(size 1 1)
					(thickness 0.15)
				)
			)
		)
		(property "Val" "0R"
			(at 40.924 267.194 0)
			(layer "F.Fab")
			(hide yes)
			(effects
				(font
					(size 1 1)
					(thickness 0.15)
				)
			)
		)
		(sheetname "Interfaces")
		(sheetfile "interfaces.kicad_sch")
		(attr smd)
		(fp_rect
			(start -0.93 -0.47)
			(end 0.93 0.47)
			(stroke
				(width 0.05)
				(type solid)
			)
			(fill no)
			(layer "F.CrtYd")
		)
		(fp_rect
			(start -0.5 -0.25)
			(end 0.5 0.25)
			(stroke
				(width 0.15)
				(type solid)
			)
			(fill no)
			(layer "F.Fab")
		)
		(pad "1" smd roundrect
			(at -0.485 0 270)
			(size 0.59 0.64)
			(layers "F.Cu" "F.Mask" "F.Paste")
			(roundrect_rratio 0.25)
			(net 45 "TMDS_CLK_N")
			(pintype "passive")
		)
		(pad "2" smd roundrect
			(at 0.485 0 270)
			(size 0.59 0.64)
			(layers "F.Cu" "F.Mask" "F.Paste")
			(roundrect_rratio 0.25)
			(net 663 "/Interfaces/C_TMDS_CLK_N")
			(pintype "passive")
		)
	)
	(footprint "antmicro-footprints:R_0402_1005Metric"
		(layer "F.Cu")
		(at 155.084 113.135 -90)
		(descr "Resistor SMD 0402")
		(tags "resistor SMD 0402")
		(property "Reference" "R40"
			(at -0.835 -0.416 270)
			(layer "F.SilkS")
			(effects
				(font
					(size 0.7 0.7)
					(thickness 0.15)
				)
				(justify left bottom)
			)
		)
		(property "Value" "R_0R_0402"
			(at 0 1.4 270)
			(layer "F.Fab")
			(effects
				(font
					(size 0.7 0.7)
					(thickness 0.15)
				)
				(justify left bottom)
			)
		)
		(property "Description" "0R resistor in 0402 package with unspecified tolerance"
			(at 0 0 270)
			(layer "F.Fab")
			(hide yes)
			(effects
				(font
					(size 1.27 1.27)
					(thickness 0.15)
				)
			)
		)
		(property "Author" "Antmicro"
			(at 41.949 268.219 0)
			(layer "F.Fab")
			(hide yes)
			(effects
				(font
					(size 1 1)
					(thickness 0.15)
				)
			)
		)
		(property "Current" "1A"
			(at 41.949 268.219 0)
			(layer "F.Fab")
			(hide yes)
			(effects
				(font
					(size 1 1)
					(thickness 0.15)
				)
			)
		)
		(property "License" "Apache-2.0"
			(at 41.949 268.219 0)
			(layer "F.Fab")
			(hide yes)
			(effects
				(font
					(size 1 1)
					(thickness 0.15)
				)
			)
		)
		(property "MPN" "ERJ2GE0R00X"
			(at 41.949 268.219 0)
			(layer "F.Fab")
			(hide yes)
			(effects
				(font
					(size 1 1)
					(thickness 0.15)
				)
			)
		)
		(property "Manufacturer" "Panasonic"
			(at 41.949 268.219 0)
			(layer "F.Fab")
			(hide yes)
			(effects
				(font
					(size 1 1)
					(thickness 0.15)
				)
			)
		)
		(property "Tolerance" ""
			(at 41.949 268.219 0)
			(layer "F.Fab")
			(hide yes)
			(effects
				(font
					(size 1 1)
					(thickness 0.15)
				)
			)
		)
		(property "Val" "0R"
			(at 41.949 268.219 0)
			(layer "F.Fab")
			(hide yes)
			(effects
				(font
					(size 1 1)
					(thickness 0.15)
				)
			)
		)
		(sheetname "Interfaces")
		(sheetfile "interfaces.kicad_sch")
		(attr smd)
		(fp_rect
			(start -0.93 -0.47)
			(end 0.93 0.47)
			(stroke
				(width 0.05)
				(type solid)
			)
			(fill no)
			(layer "F.CrtYd")
		)
		(fp_rect
			(start -0.5 -0.25)
			(end 0.5 0.25)
			(stroke
				(width 0.15)
				(type solid)
			)
			(fill no)
			(layer "F.Fab")
		)
		(pad "1" smd roundrect
			(at -0.485 0 270)
			(size 0.59 0.64)
			(layers "F.Cu" "F.Mask" "F.Paste")
			(roundrect_rratio 0.25)
			(net 44 "TMDS_CLK_P")
			(pintype "passive")
		)
		(pad "2" smd roundrect
			(at 0.485 0 270)
			(size 0.59 0.64)
			(layers "F.Cu" "F.Mask" "F.Paste")
			(roundrect_rratio 0.25)
			(net 664 "/Interfaces/C_TMDS_CLK_P")
			(pintype "passive")
		)
	)
	(footprint "antmicro-footprints:R_0402_1005Metric"
		(layer "F.Cu")
		(at 155.559 115.35 -90)
		(descr "Resistor SMD 0402")
		(tags "resistor SMD 0402")
		(property "Reference" "R41"
			(at 1.25 1.559 270)
			(layer "F.SilkS")
			(effects
				(font
					(size 0.7 0.7)
					(thickness 0.15)
				)
				(justify left bottom)
			)
		)
		(property "Value" "R_0R_0402"
			(at 0 1.4 270)
			(layer "F.Fab")
			(effects
				(font
					(size 0.7 0.7)
					(thickness 0.15)
				)
				(justify left bottom)
			)
		)
		(property "Description" "0R resistor in 0402 package with unspecified tolerance"
			(at 0 0 270)
			(layer "F.Fab")
			(hide yes)
			(effects
				(font
					(size 1.27 1.27)
					(thickness 0.15)
				)
			)
		)
		(property "Author" "Antmicro"
			(at 40.209 270.909 0)
			(layer "F.Fab")
			(hide yes)
			(effects
				(font
					(size 1 1)
					(thickness 0.15)
				)
			)
		)
		(property "Current" "1A"
			(at 40.209 270.909 0)
			(layer "F.Fab")
			(hide yes)
			(effects
				(font
					(size 1 1)
					(thickness 0.15)
				)
			)
		)
		(property "License" "Apache-2.0"
			(at 40.209 270.909 0)
			(layer "F.Fab")
			(hide yes)
			(effects
				(font
					(size 1 1)
					(thickness 0.15)
				)
			)
		)
		(property "MPN" "ERJ2GE0R00X"
			(at 40.209 270.909 0)
			(layer "F.Fab")
			(hide yes)
			(effects
				(font
					(size 1 1)
					(thickness 0.15)
				)
			)
		)
		(property "Manufacturer" "Panasonic"
			(at 40.209 270.909 0)
			(layer "F.Fab")
			(hide yes)
			(effects
				(font
					(size 1 1)
					(thickness 0.15)
				)
			)
		)
		(property "Tolerance" ""
			(at 40.209 270.909 0)
			(layer "F.Fab")
			(hide yes)
			(effects
				(font
					(size 1 1)
					(thickness 0.15)
				)
			)
		)
		(property "Val" "0R"
			(at 40.209 270.909 0)
			(layer "F.Fab")
			(hide yes)
			(effects
				(font
					(size 1 1)
					(thickness 0.15)
				)
			)
		)
		(sheetname "Interfaces")
		(sheetfile "interfaces.kicad_sch")
		(attr smd)
		(fp_rect
			(start -0.93 -0.47)
			(end 0.93 0.47)
			(stroke
				(width 0.05)
				(type solid)
			)
			(fill no)
			(layer "F.CrtYd")
		)
		(fp_rect
			(start -0.5 -0.25)
			(end 0.5 0.25)
			(stroke
				(width 0.15)
				(type solid)
			)
			(fill no)
			(layer "F.Fab")
		)
		(pad "1" smd roundrect
			(at -0.485 0 270)
			(size 0.59 0.64)
			(layers "F.Cu" "F.Mask" "F.Paste")
			(roundrect_rratio 0.25)
			(net 47 "TMDS_D0_N")
			(pintype "passive")
		)
		(pad "2" smd roundrect
			(at 0.485 0 270)
			(size 0.59 0.64)
			(layers "F.Cu" "F.Mask" "F.Paste")
			(roundrect_rratio 0.25)
			(net 665 "/Interfaces/C_TMDS_D0_N")
			(pintype "passive")
		)
	)
	(footprint "antmicro-footprints:R_0402_1005Metric"
		(layer "F.Cu")
		(at 156.584 115.35 -90)
		(descr "Resistor SMD 0402")
		(tags "resistor SMD 0402")
		(property "Reference" "R42"
			(at 1.25 1.559 270)
			(layer "F.SilkS")
			(effects
				(font
					(size 0.7 0.7)
					(thickness 0.15)
				)
				(justify left bottom)
			)
		)
		(property "Value" "R_0R_0402"
			(at 0 1.4 270)
			(layer "F.Fab")
			(effects
				(font
					(size 0.7 0.7)
					(thickness 0.15)
				)
				(justify left bottom)
			)
		)
		(property "Description" "0R resistor in 0402 package with unspecified tolerance"
			(at 0 0 270)
			(layer "F.Fab")
			(hide yes)
			(effects
				(font
					(size 1.27 1.27)
					(thickness 0.15)
				)
			)
		)
		(property "Author" "Antmicro"
			(at 41.234 271.934 0)
			(layer "F.Fab")
			(hide yes)
			(effects
				(font
					(size 1 1)
					(thickness 0.15)
				)
			)
		)
		(property "Current" "1A"
			(at 41.234 271.934 0)
			(layer "F.Fab")
			(hide yes)
			(effects
				(font
					(size 1 1)
					(thickness 0.15)
				)
			)
		)
		(property "License" "Apache-2.0"
			(at 41.234 271.934 0)
			(layer "F.Fab")
			(hide yes)
			(effects
				(font
					(size 1 1)
					(thickness 0.15)
				)
			)
		)
		(property "MPN" "ERJ2GE0R00X"
			(at 41.234 271.934 0)
			(layer "F.Fab")
			(hide yes)
			(effects
				(font
					(size 1 1)
					(thickness 0.15)
				)
			)
		)
		(property "Manufacturer" "Panasonic"
			(at 41.234 271.934 0)
			(layer "F.Fab")
			(hide yes)
			(effects
				(font
					(size 1 1)
					(thickness 0.15)
				)
			)
		)
		(property "Tolerance" ""
			(at 41.234 271.934 0)
			(layer "F.Fab")
			(hide yes)
			(effects
				(font
					(size 1 1)
					(thickness 0.15)
				)
			)
		)
		(property "Val" "0R"
			(at 41.234 271.934 0)
			(layer "F.Fab")
			(hide yes)
			(effects
				(font
					(size 1 1)
					(thickness 0.15)
				)
			)
		)
		(sheetname "Interfaces")
		(sheetfile "interfaces.kicad_sch")
		(attr smd)
		(fp_rect
			(start -0.93 -0.47)
			(end 0.93 0.47)
			(stroke
				(width 0.05)
				(type solid)
			)
			(fill no)
			(layer "F.CrtYd")
		)
		(fp_rect
			(start -0.5 -0.25)
			(end 0.5 0.25)
			(stroke
				(width 0.15)
				(type solid)
			)
			(fill no)
			(layer "F.Fab")
		)
		(pad "1" smd roundrect
			(at -0.485 0 270)
			(size 0.59 0.64)
			(layers "F.Cu" "F.Mask" "F.Paste")
			(roundrect_rratio 0.25)
			(net 46 "TMDS_D0_P")
			(pintype "passive")
		)
		(pad "2" smd roundrect
			(at 0.485 0 270)
			(size 0.59 0.64)
			(layers "F.Cu" "F.Mask" "F.Paste")
			(roundrect_rratio 0.25)
			(net 666 "/Interfaces/C_TMDS_D0_P")
			(pintype "passive")
		)
	)
	(footprint "antmicro-footprints:R_0402_1005Metric"
		(layer "F.Cu")
		(at 158.104 113.05 -90)
		(descr "Resistor SMD 0402")
		(tags "resistor SMD 0402")
		(property "Reference" "R44"
			(at -0.835 -0.416 270)
			(layer "F.SilkS")
			(effects
				(font
					(size 0.7 0.7)
					(thickness 0.15)
				)
				(justify left bottom)
			)
		)
		(property "Value" "R_0R_0402"
			(at 0 1.4 270)
			(layer "F.Fab")
			(effects
				(font
					(size 0.7 0.7)
					(thickness 0.15)
				)
				(justify left bottom)
			)
		)
		(property "Description" "0R resistor in 0402 package with unspecified tolerance"
			(at 0 0 270)
			(layer "F.Fab")
			(hide yes)
			(effects
				(font
					(size 1.27 1.27)
					(thickness 0.15)
				)
			)
		)
		(property "Author" "Antmicro"
			(at 45.054 271.154 0)
			(layer "F.Fab")
			(hide yes)
			(effects
				(font
					(size 1 1)
					(thickness 0.15)
				)
			)
		)
		(property "Current" "1A"
			(at 45.054 271.154 0)
			(layer "F.Fab")
			(hide yes)
			(effects
				(font
					(size 1 1)
					(thickness 0.15)
				)
			)
		)
		(property "License" "Apache-2.0"
			(at 45.054 271.154 0)
			(layer "F.Fab")
			(hide yes)
			(effects
				(font
					(size 1 1)
					(thickness 0.15)
				)
			)
		)
		(property "MPN" "ERJ2GE0R00X"
			(at 45.054 271.154 0)
			(layer "F.Fab")
			(hide yes)
			(effects
				(font
					(size 1 1)
					(thickness 0.15)
				)
			)
		)
		(property "Manufacturer" "Panasonic"
			(at 45.054 271.154 0)
			(layer "F.Fab")
			(hide yes)
			(effects
				(font
					(size 1 1)
					(thickness 0.15)
				)
			)
		)
		(property "Tolerance" ""
			(at 45.054 271.154 0)
			(layer "F.Fab")
			(hide yes)
			(effects
				(font
					(size 1 1)
					(thickness 0.15)
				)
			)
		)
		(property "Val" "0R"
			(at 45.054 271.154 0)
			(layer "F.Fab")
			(hide yes)
			(effects
				(font
					(size 1 1)
					(thickness 0.15)
				)
			)
		)
		(sheetname "Interfaces")
		(sheetfile "interfaces.kicad_sch")
		(attr smd)
		(fp_rect
			(start -0.93 -0.47)
			(end 0.93 0.47)
			(stroke
				(width 0.05)
				(type solid)
			)
			(fill no)
			(layer "F.CrtYd")
		)
		(fp_rect
			(start -0.5 -0.25)
			(end 0.5 0.25)
			(stroke
				(width 0.15)
				(type solid)
			)
			(fill no)
			(layer "F.Fab")
		)
		(pad "1" smd roundrect
			(at -0.485 0 270)
			(size 0.59 0.64)
			(layers "F.Cu" "F.Mask" "F.Paste")
			(roundrect_rratio 0.25)
			(net 48 "TMDS_D1_P")
			(pintype "passive")
		)
		(pad "2" smd roundrect
			(at 0.485 0 270)
			(size 0.59 0.64)
			(layers "F.Cu" "F.Mask" "F.Paste")
			(roundrect_rratio 0.25)
			(net 668 "/Interfaces/C_TMDS_D1_P")
			(pintype "passive")
		)
	)
	(footprint "antmicro-footprints:R_0402_1005Metric"
		(layer "F.Cu")
		(at 158.643 115.477 -90)
		(descr "Resistor SMD 0402")
		(tags "resistor SMD 0402")
		(property "Reference" "R45"
			(at 1.25 -2.341 270)
			(layer "F.SilkS")
			(effects
				(font
					(size 0.7 0.7)
					(thickness 0.15)
				)
				(justify left bottom)
			)
		)
		(property "Value" "R_0R_0402"
			(at 0 1.4 270)
			(layer "F.Fab")
			(effects
				(font
					(size 0.7 0.7)
					(thickness 0.15)
				)
				(justify left bottom)
			)
		)
		(property "Description" "0R resistor in 0402 package with unspecified tolerance"
			(at 0 0 270)
			(layer "F.Fab")
			(hide yes)
			(effects
				(font
					(size 1.27 1.27)
					(thickness 0.15)
				)
			)
		)
		(property "Author" "Antmicro"
			(at 43.166 274.12 0)
			(layer "F.Fab")
			(hide yes)
			(effects
				(font
					(size 1 1)
					(thickness 0.15)
				)
			)
		)
		(property "Current" "1A"
			(at 43.166 274.12 0)
			(layer "F.Fab")
			(hide yes)
			(effects
				(font
					(size 1 1)
					(thickness 0.15)
				)
			)
		)
		(property "License" "Apache-2.0"
			(at 43.166 274.12 0)
			(layer "F.Fab")
			(hide yes)
			(effects
				(font
					(size 1 1)
					(thickness 0.15)
				)
			)
		)
		(property "MPN" "ERJ2GE0R00X"
			(at 43.166 274.12 0)
			(layer "F.Fab")
			(hide yes)
			(effects
				(font
					(size 1 1)
					(thickness 0.15)
				)
			)
		)
		(property "Manufacturer" "Panasonic"
			(at 43.166 274.12 0)
			(layer "F.Fab")
			(hide yes)
			(effects
				(font
					(size 1 1)
					(thickness 0.15)
				)
			)
		)
		(property "Tolerance" ""
			(at 43.166 274.12 0)
			(layer "F.Fab")
			(hide yes)
			(effects
				(font
					(size 1 1)
					(thickness 0.15)
				)
			)
		)
		(property "Val" "0R"
			(at 43.166 274.12 0)
			(layer "F.Fab")
			(hide yes)
			(effects
				(font
					(size 1 1)
					(thickness 0.15)
				)
			)
		)
		(sheetname "Interfaces")
		(sheetfile "interfaces.kicad_sch")
		(attr smd)
		(fp_rect
			(start -0.93 -0.47)
			(end 0.93 0.47)
			(stroke
				(width 0.05)
				(type solid)
			)
			(fill no)
			(layer "F.CrtYd")
		)
		(fp_rect
			(start -0.5 -0.25)
			(end 0.5 0.25)
			(stroke
				(width 0.15)
				(type solid)
			)
			(fill no)
			(layer "F.Fab")
		)
		(pad "1" smd roundrect
			(at -0.485 0 270)
			(size 0.59 0.64)
			(layers "F.Cu" "F.Mask" "F.Paste")
			(roundrect_rratio 0.25)
			(net 51 "TMDS_D2_N")
			(pintype "passive")
		)
		(pad "2" smd roundrect
			(at 0.485 0 270)
			(size 0.59 0.64)
			(layers "F.Cu" "F.Mask" "F.Paste")
			(roundrect_rratio 0.25)
			(net 669 "/Interfaces/C_TMDS_D2_N")
			(pintype "passive")
		)
	)
)
